(kicad_pcb
	(version 20221018)
	(generator pcbnew)
	(general
    (thickness 1.562)
  )
	(paper "A4")
	(title_block
    (title "Thunderbolt PCIe Adaper")
    (date "2024-07-09")
    (rev "1.0.3")
    (comment 1 "www.antmicro.com")
    (comment 2 "Antmicro Ltd.")
		(comment 9 "footprints 97-105 of 271")
	)
	(layers
    (0 "F.Cu" signal)
    (1 "In1.Cu" signal)
    (2 "In2.Cu" signal)
    (3 "In3.Cu" signal)
    (4 "In4.Cu" signal)
    (31 "B.Cu" signal)
    (32 "B.Adhes" user "B.Adhesive")
    (33 "F.Adhes" user "F.Adhesive")
    (34 "B.Paste" user)
    (35 "F.Paste" user)
    (36 "B.SilkS" user "B.Silkscreen")
    (37 "F.SilkS" user "F.Silkscreen")
    (38 "B.Mask" user)
    (39 "F.Mask" user)
    (40 "Dwgs.User" user "User.Drawings")
    (41 "Cmts.User" user "User.Comments")
    (42 "Eco1.User" user "User.Eco1")
    (43 "Eco2.User" user "User.Eco2")
    (44 "Edge.Cuts" user)
    (45 "Margin" user)
    (46 "B.CrtYd" user "B.Courtyard")
    (47 "F.CrtYd" user "F.Courtyard")
    (48 "B.Fab" user)
    (49 "F.Fab" user)
  )
	(footprint "antmicro-footprints:R_0402_1005Metric" (layer "B.Cu")
    (at 148.5 70.94 90)
    (descr "Resistor SMD 0402")
    (tags "resistor SMD 0402")
    (property "Author" "Antmicro")
    (property "License" "Apache-2.0")
    (property "MPN" "CR0402-FX-3300GLF")
    (property "Manufacturer" "Bourns")
    (property "Sheetfile" "tb-power.kicad_sch")
    (property "Sheetname" "Thunderbolt Controller - Power")
    (property "Tolerance" "1%")
    (property "Val" "330R")
    (property "ki_description" "SMD Chip Resistor, 330 ohm, ± 1%, 62.5 mW, 0402 [1005 Metric], Thick Film, General Purpose")
    (property "ki_keywords" "0402, SMT, RESISTOR, PASSIVE")
    (attr smd)
    (fp_text reference "R49" (at 3.122 0.455 270) (layer "B.SilkS")
        (effects (font (size 0.7 0.7) (thickness 0.15)) (justify left bottom mirror))
    )
    (fp_text value "R_330R_0402" (at -1.011843 -1.772047 270) (layer "B.Fab")
        (effects (font (size 0.7 0.7) (thickness 0.15)) (justify left bottom mirror))
    )
    (fp_text user "Author: Antmicro" (at -0.95 -4.169 270) (layer "B.Fab") hide
        (effects (font (size 0.7 0.7) (thickness 0.15)) (justify left bottom mirror))
    )
    (fp_text user "${REFERENCE}" (at -0.95 -3.168 270) (layer "B.Fab") hide
        (effects (font (size 0.7 0.7) (thickness 0.15)) (justify left bottom mirror))
    )
    (fp_text user "License: Apache-2.0" (at -0.95 -5.169 270) (layer "B.Fab") hide
        (effects (font (size 0.7 0.7) (thickness 0.15)) (justify left bottom mirror))
    )
    (fp_rect (start -0.925 0.47) (end 0.925 -0.47)
      (stroke (width 0.05) (type default)) (fill none) (layer "B.CrtYd"))
    (fp_rect (start -0.5 0.25) (end 0.5 -0.25)
      (stroke (width 0.15) (type solid)) (fill none) (layer "B.Fab"))
    (pad "1" smd roundrect (at -0.48 0 90) (size 0.59 0.64) (layers "B.Cu" "B.Paste" "B.Mask") (roundrect_rratio 0.25)
      (net 139 "Net-(Q1-C)") (pintype "passive"))
    (pad "2" smd roundrect (at 0.48 0 90) (size 0.59 0.64) (layers "B.Cu" "B.Paste" "B.Mask") (roundrect_rratio 0.25)
      (net 122 "Net-(D4-C)") (pintype "passive"))
  )
	(footprint "antmicro-footprints:C_0603_1608Metric" (layer "B.Cu")
    (at 163.43 89.8 90)
    (descr "Capacitor SMD 0603")
    (tags "capacitor 0603")
    (property "Author" "Antmicro")
    (property "Dielectric" "")
    (property "License" "Apache-2.0")
    (property "MPN" "CL10A226MO7JZNC")
    (property "Manufacturer" "Samsung Electro-Mechanics")
    (property "Sheetfile" "power.kicad_sch")
    (property "Sheetname" "Power")
    (property "Val" "22u")
    (property "Voltage" "16V")
    (property "ki_description" "SMD Multilayer Ceramic Capacitor")
    (property "ki_keywords" "0603, SMT, CAPACITOR, PASSIVE, CERAMIC")
    (attr smd)
    (fp_text reference "C122" (at 4.202 0.4 270) (layer "B.SilkS")
        (effects (font (size 0.7 0.7) (thickness 0.15)) (justify left bottom mirror))
    )
    (fp_text value "C_22u_16V_0603" (at -1.42757 -1.770288 270) (layer "B.Fab")
        (effects (font (size 0.7 0.7) (thickness 0.15)) (justify left bottom mirror))
    )
    (fp_text user "License: Apache-2.0" (at -1.682 -5.895 270) (layer "B.Fab") hide
        (effects (font (size 0.7 0.7) (thickness 0.15)) (justify left bottom mirror))
    )
    (fp_text user "Author: Antmicro" (at -1.682 -4.894 270) (layer "B.Fab") hide
        (effects (font (size 0.7 0.7) (thickness 0.15)) (justify left bottom mirror))
    )
    (fp_text user "${REFERENCE}" (at -1.682 -3.895 270) (layer "B.Fab") hide
        (effects (font (size 0.7 0.7) (thickness 0.15)) (justify left bottom mirror))
    )
    (fp_line (start -0.15 -0.4) (end 0.15 -0.4)
      (stroke (width 0.15) (type solid)) (layer "B.SilkS"))
    (fp_line (start -0.15 0.4) (end 0.15 0.4)
      (stroke (width 0.15) (type solid)) (layer "B.SilkS"))
    (fp_rect (start -1.25 0.65) (end 1.25 -0.65)
      (stroke (width 0.05) (type solid)) (fill none) (layer "B.CrtYd"))
    (fp_rect (start -0.8 0.4) (end 0.8 -0.4)
      (stroke (width 0.15) (type solid)) (fill none) (layer "B.Fab"))
    (pad "1" smd roundrect (at -0.7 0 90) (size 0.8 1) (layers "B.Cu" "B.Paste" "B.Mask") (roundrect_rratio 0.2)
      (net 1 "GND") (pintype "passive"))
    (pad "2" smd roundrect (at 0.7 0 90) (size 0.8 1) (layers "B.Cu" "B.Paste" "B.Mask") (roundrect_rratio 0.2)
      (net 61 "12V0_MOLEX") (pintype "passive"))
  )
	(footprint "antmicro-footprints:C_0402_1005Metric" (layer "B.Cu")
    (at 132.85 80.825)
    (descr "Capacitor SMD 0402")
    (tags "capacitor SMD 0402")
    (property "Author" "Antmicro")
    (property "Dielectric" "X5R")
    (property "License" "Apache-2.0")
    (property "MPN" "GRM155R61H104KE14D")
    (property "Manufacturer" "Murata")
    (property "Sheetfile" "tb-power.kicad_sch")
    (property "Sheetname" "Thunderbolt Controller - Power")
    (property "Val" "100n")
    (property "Voltage" "50V")
    (property "ki_description" "SMD Multilayer Ceramic Capacitor, 0.1 µF, 50 V, 0402 [1005 Metric], ± 10%, X5R, GRM Series")
    (property "ki_keywords" "0402, SMT, CAPACITOR, PASSIVE, CERAMIC, MLCC")
    (attr smd)
    (fp_text reference "C92" (at 17.518 7.694 180) (layer "B.SilkS")
        (effects (font (size 0.7 0.7) (thickness 0.15)) (justify left bottom mirror))
    )
    (fp_text value "C_100n_0402" (at -1.022927 -2.155213 180) (layer "B.Fab")
        (effects (font (size 0.7 0.7) (thickness 0.15)) (justify left bottom mirror))
    )
    (fp_text user "Author: Antmicro" (at -0.939 -3.399 180) (layer "B.Fab") hide
        (effects (font (size 0.7 0.7) (thickness 0.15)) (justify left bottom mirror))
    )
    (fp_text user "License: Apache-2.0" (at -0.939 -5.799 180) (layer "B.Fab") hide
        (effects (font (size 0.7 0.7) (thickness 0.15)) (justify left bottom mirror))
    )
    (fp_text user "${REFERENCE}" (at -0.939 -4.599 180) (layer "B.Fab") hide
        (effects (font (size 0.7 0.7) (thickness 0.15)) (justify left bottom mirror))
    )
    (fp_rect (start -0.925 0.47) (end 0.925 -0.47)
      (stroke (width 0.05) (type default)) (fill none) (layer "B.CrtYd"))
    (fp_line (start -0.494 -0.248) (end -0.494 0.25)
      (stroke (width 0.15) (type solid)) (layer "B.Fab"))
    (fp_line (start -0.494 0.25) (end 0.504 0.25)
      (stroke (width 0.15) (type solid)) (layer "B.Fab"))
    (fp_line (start 0.504 -0.248) (end -0.494 -0.248)
      (stroke (width 0.15) (type solid)) (layer "B.Fab"))
    (fp_line (start 0.504 0.25) (end 0.504 -0.248)
      (stroke (width 0.15) (type solid)) (layer "B.Fab"))
    (pad "1" smd roundrect (at -0.48 0) (size 0.59 0.64) (layers "B.Cu" "B.Paste" "B.Mask") (roundrect_rratio 0.25)
      (net 1 "GND") (pintype "passive"))
    (pad "2" smd roundrect (at 0.48 0) (size 0.59 0.64) (layers "B.Cu" "B.Paste" "B.Mask") (roundrect_rratio 0.25)
      (net 114 "Net-(U4A-VCC3P3_S0)") (pintype "passive"))
  )
	(footprint "antmicro-footprints:C_0402_1005Metric" (layer "B.Cu")
    (at 142.682242 89.259183 45)
    (descr "Capacitor SMD 0402")
    (tags "capacitor SMD 0402")
    (property "Author" "Antmicro")
    (property "Dielectric" "C0G")
    (property "License" "Apache-2.0")
    (property "MPN" "GCM1555C1H100GA16D")
    (property "Manufacturer" "Murata")
    (property "Sheetfile" "tb.kicad_sch")
    (property "Sheetname" "TB Controller")
    (property "Val" "10p")
    (property "Voltage" "50V")
    (property "ki_description" "SMD Multilayer Ceramic Capacitor, 10 pF, 50 V, 0402 [1005 Metric], ± 2%, C0G / NP0, GCM")
    (property "ki_keywords" "0402, SMT, CAPACITOR, PASSIVE")
    (attr smd)
    (fp_text reference "C117" (at 1.827122 -0.656496 225) (layer "B.SilkS")
        (effects (font (size 0.7 0.7) (thickness 0.15)) (justify left bottom mirror))
    )
    (fp_text value "C_10p_0402" (at -1.022927 -2.155213 225) (layer "B.Fab")
        (effects (font (size 0.7 0.7) (thickness 0.15)) (justify left bottom mirror))
    )
    (fp_text user "${REFERENCE}" (at -0.939 -4.599 225) (layer "B.Fab") hide
        (effects (font (size 0.7 0.7) (thickness 0.15)) (justify left bottom mirror))
    )
    (fp_text user "Author: Antmicro" (at -0.939 -3.399 225) (layer "B.Fab") hide
        (effects (font (size 0.7 0.7) (thickness 0.15)) (justify left bottom mirror))
    )
    (fp_text user "License: Apache-2.0" (at -0.939 -5.799 225) (layer "B.Fab") hide
        (effects (font (size 0.7 0.7) (thickness 0.15)) (justify left bottom mirror))
    )
    (fp_rect (start -0.925 0.47) (end 0.925 -0.47)
      (stroke (width 0.05) (type default)) (fill none) (layer "B.CrtYd"))
    (fp_line (start -0.494 -0.248) (end -0.494 0.25)
      (stroke (width 0.15) (type solid)) (layer "B.Fab"))
    (fp_line (start -0.494 0.25) (end 0.504 0.25)
      (stroke (width 0.15) (type solid)) (layer "B.Fab"))
    (fp_line (start 0.504 -0.248) (end -0.494 -0.248)
      (stroke (width 0.15) (type solid)) (layer "B.Fab"))
    (fp_line (start 0.504 0.25) (end 0.504 -0.248)
      (stroke (width 0.15) (type solid)) (layer "B.Fab"))
    (pad "1" smd roundrect (at -0.48 0 45) (size 0.59 0.64) (layers "B.Cu" "B.Paste" "B.Mask") (roundrect_rratio 0.25)
      (net 118 "Net-(U4D-XTAL_25_OUT)") (pintype "passive"))
    (pad "2" smd roundrect (at 0.48 0 45) (size 0.59 0.64) (layers "B.Cu" "B.Paste" "B.Mask") (roundrect_rratio 0.25)
      (net 1 "GND") (pintype "passive"))
  )
	(footprint "antmicro-footprints:R_0402_1005Metric" (layer "B.Cu")
    (at 151.41 62.97)
    (descr "Resistor SMD 0402")
    (tags "resistor SMD 0402")
    (property "Author" "Antmicro")
    (property "Current" "1A")
    (property "License" "Apache-2.0")
    (property "MPN" "ERJ2GE0R00X")
    (property "Manufacturer" "Panasonic")
    (property "Sheetfile" "power.kicad_sch")
    (property "Sheetname" "Power")
    (property "Tolerance" "")
    (property "Val" "0R")
    (property "ki_description" "SMD Chip Resistor, Jumper, 0 ohm, 100 mW, 0402 [1005 Metric], Thick Film, General Purpose")
    (property "ki_keywords" "0402, SMT, RESISTOR, PASSIVE")
    (attr smd)
    (fp_text reference "R31" (at -0.915 0.482 180) (layer "B.SilkS")
        (effects (font (size 0.7 0.7) (thickness 0.15)) (justify left bottom mirror))
    )
    (fp_text value "R_0R_0402" (at -1.011843 -1.772047 180) (layer "B.Fab")
        (effects (font (size 0.7 0.7) (thickness 0.15)) (justify left bottom mirror))
    )
    (fp_text user "${REFERENCE}" (at -0.95 -3.168 180) (layer "B.Fab") hide
        (effects (font (size 0.7 0.7) (thickness 0.15)) (justify left bottom mirror))
    )
    (fp_text user "Author: Antmicro" (at -0.95 -4.169 180) (layer "B.Fab") hide
        (effects (font (size 0.7 0.7) (thickness 0.15)) (justify left bottom mirror))
    )
    (fp_text user "License: Apache-2.0" (at -0.95 -5.169 180) (layer "B.Fab") hide
        (effects (font (size 0.7 0.7) (thickness 0.15)) (justify left bottom mirror))
    )
    (fp_rect (start -0.925 0.47) (end 0.925 -0.47)
      (stroke (width 0.05) (type default)) (fill none) (layer "B.CrtYd"))
    (fp_rect (start -0.5 0.25) (end 0.5 -0.25)
      (stroke (width 0.15) (type solid)) (fill none) (layer "B.Fab"))
    (pad "1" smd roundrect (at -0.48 0) (size 0.59 0.64) (layers "B.Cu" "B.Paste" "B.Mask") (roundrect_rratio 0.25)
      (net 164 "Net-(U3-I2C_ADDR)") (pintype "passive"))
    (pad "2" smd roundrect (at 0.48 0) (size 0.59 0.64) (layers "B.Cu" "B.Paste" "B.Mask") (roundrect_rratio 0.25)
      (net 1 "GND") (pintype "passive"))
  )
	(footprint "antmicro-footprints:C_0402_1005Metric" (layer "B.Cu")
    (at 153.91 60.47 -90)
    (descr "Capacitor SMD 0402")
    (tags "capacitor SMD 0402")
    (property "Author" "Antmicro")
    (property "Dielectric" "")
    (property "License" "Apache-2.0")
    (property "MPN" "C1005X6S1A105K050BC")
    (property "Manufacturer" "TDK")
    (property "Sheetfile" "power.kicad_sch")
    (property "Sheetname" "Power")
    (property "Val" "1u")
    (property "Voltage" "")
    (property "ki_description" "SMD Multilayer Ceramic Capacitor, 1 µF, 10 V, 0402 [1005 Metric], ± 10%, X6S, C")
    (property "ki_keywords" "0402, SMT, CAPACITOR, PASSIVE, CERAMIC, MLCC")
    (attr smd)
    (fp_text reference "C22" (at -3.193 -0.268 90) (layer "B.SilkS")
        (effects (font (size 0.7 0.7) (thickness 0.15)) (justify left bottom mirror))
    )
    (fp_text value "C_1u_0402" (at -1.022927 -2.155213 90) (layer "B.Fab")
        (effects (font (size 0.7 0.7) (thickness 0.15)) (justify left bottom mirror))
    )
    (fp_text user "Author: Antmicro" (at -0.939 -3.399 90) (layer "B.Fab") hide
        (effects (font (size 0.7 0.7) (thickness 0.15)) (justify left bottom mirror))
    )
    (fp_text user "${REFERENCE}" (at -0.939 -4.599 90) (layer "B.Fab") hide
        (effects (font (size 0.7 0.7) (thickness 0.15)) (justify left bottom mirror))
    )
    (fp_text user "License: Apache-2.0" (at -0.939 -5.799 90) (layer "B.Fab") hide
        (effects (font (size 0.7 0.7) (thickness 0.15)) (justify left bottom mirror))
    )
    (fp_rect (start -0.925 0.47) (end 0.925 -0.47)
      (stroke (width 0.05) (type default)) (fill none) (layer "B.CrtYd"))
    (fp_line (start -0.494 -0.248) (end -0.494 0.25)
      (stroke (width 0.15) (type solid)) (layer "B.Fab"))
    (fp_line (start -0.494 0.25) (end 0.504 0.25)
      (stroke (width 0.15) (type solid)) (layer "B.Fab"))
    (fp_line (start 0.504 -0.248) (end -0.494 -0.248)
      (stroke (width 0.15) (type solid)) (layer "B.Fab"))
    (fp_line (start 0.504 0.25) (end 0.504 -0.248)
      (stroke (width 0.15) (type solid)) (layer "B.Fab"))
    (pad "1" smd roundrect (at -0.48 0 270) (size 0.59 0.64) (layers "B.Cu" "B.Paste" "B.Mask") (roundrect_rratio 0.25)
      (net 1 "GND") (pintype "passive"))
    (pad "2" smd roundrect (at 0.48 0 270) (size 0.59 0.64) (layers "B.Cu" "B.Paste" "B.Mask") (roundrect_rratio 0.25)
      (net 2 "3V3_SYS") (pintype "passive"))
  )
	(footprint "antmicro-footprints:L_0603_1608Metric" (layer "B.Cu")
    (at 128.44 82.04)
    (property "Author" "Antmicro")
    (property "IMax" "1.8A")
    (property "ISat" "1.9A")
    (property "License" "Apache-2.0")
    (property "MPN" "DFE18SBN1R0ME0L")
    (property "Manufacturer" "Murata")
    (property "Sheetfile" "tb-power.kicad_sch")
    (property "Sheetname" "Thunderbolt Controller - Power")
    (property "Size" "1.6x0.8")
    (property "Val" "1u/1.8A")
    (property "ki_description" "Power Inductor (SMT), 1 µH, 1.8 A, Shielded, 1.9 A, DFE Series, 0603 [1608 Metric]")
    (property "ki_keywords" "INDUCTOR, PASSIVE")
    (attr smd)
    (fp_text reference "L4" (at 0.592 1.653 180) (layer "B.SilkS")
        (effects (font (size 0.7 0.7) (thickness 0.15)) (justify left bottom mirror))
    )
    (fp_text value "L_1u_1.8A_0603" (at 0 -2 180) (layer "B.Fab")
        (effects (font (size 0.7 0.7) (thickness 0.15)) (justify left bottom mirror))
    )
    (fp_text user "License: Apache-2.0" (at -1.9 -5.75 180) (layer "B.Fab") hide
        (effects (font (size 0.7 0.7) (thickness 0.15)) (justify left bottom mirror))
    )
    (fp_text user "Author: Antmicro" (at -1.9 -4.4 180) (layer "B.Fab") hide
        (effects (font (size 0.7 0.7) (thickness 0.15)) (justify left bottom mirror))
    )
    (fp_text user "${REFERENCE}" (at -1.9 -3.1 180) (layer "B.Fab") hide
        (effects (font (size 0.7 0.7) (thickness 0.15)) (justify left bottom mirror))
    )
    (fp_line (start -0.15 -0.4) (end 0.15 -0.4)
      (stroke (width 0.15) (type solid)) (layer "B.SilkS"))
    (fp_line (start -0.15 0.4) (end 0.15 0.4)
      (stroke (width 0.15) (type solid)) (layer "B.SilkS"))
    (fp_rect (start -1.25 0.65) (end 1.25 -0.65)
      (stroke (width 0.05) (type solid)) (fill none) (layer "B.CrtYd"))
    (fp_rect (start -0.8 0.4) (end 0.8 -0.4)
      (stroke (width 0.1) (type solid)) (fill none) (layer "B.Fab"))
    (pad "1" smd roundrect (at -0.7 0) (size 0.8 1) (layers "B.Cu" "B.Paste" "B.Mask") (roundrect_rratio 0.2)
      (net 114 "Net-(U4A-VCC3P3_S0)") (pintype "passive"))
    (pad "2" smd roundrect (at 0.7 0) (size 0.8 1) (layers "B.Cu" "B.Paste" "B.Mask") (roundrect_rratio 0.2)
      (net 2 "3V3_SYS") (pintype "passive"))
  )
	(footprint "antmicro-footprints:R_0402_1005Metric" (layer "B.Cu")
    (at 159.425 60.97 180)
    (descr "Resistor SMD 0402")
    (tags "resistor SMD 0402")
    (property "Author" "Antmicro")
    (property "Current" "1A")
    (property "License" "Apache-2.0")
    (property "MPN" "ERJ2GE0R00X")
    (property "Manufacturer" "Panasonic")
    (property "Sheetfile" "power.kicad_sch")
    (property "Sheetname" "Power")
    (property "Tolerance" "")
    (property "Val" "0R")
    (property "ki_description" "SMD Chip Resistor, Jumper, 0 ohm, 100 mW, 0402 [1005 Metric], Thick Film, General Purpose")
    (property "ki_keywords" "0402, SMT, RESISTOR, PASSIVE")
    (attr smd)
    (fp_text reference "R18" (at -1.160616 -2.261603) (layer "B.SilkS")
        (effects (font (size 0.7 0.7) (thickness 0.15)) (justify left bottom mirror))
    )
    (fp_text value "R_0R_0402" (at -1.011843 -1.772047) (layer "B.Fab")
        (effects (font (size 0.7 0.7) (thickness 0.15)) (justify left bottom mirror))
    )
    (fp_text user "${REFERENCE}" (at -0.95 -3.168) (layer "B.Fab") hide
        (effects (font (size 0.7 0.7) (thickness 0.15)) (justify left bottom mirror))
    )
    (fp_text user "License: Apache-2.0" (at -0.95 -5.169) (layer "B.Fab") hide
        (effects (font (size 0.7 0.7) (thickness 0.15)) (justify left bottom mirror))
    )
    (fp_text user "Author: Antmicro" (at -0.95 -4.169) (layer "B.Fab") hide
        (effects (font (size 0.7 0.7) (thickness 0.15)) (justify left bottom mirror))
    )
    (fp_rect (start -0.925 0.47) (end 0.925 -0.47)
      (stroke (width 0.05) (type default)) (fill none) (layer "B.CrtYd"))
    (fp_rect (start -0.5 0.25) (end 0.5 -0.25)
      (stroke (width 0.15) (type solid)) (fill none) (layer "B.Fab"))
    (pad "1" smd roundrect (at -0.48 0 180) (size 0.59 0.64) (layers "B.Cu" "B.Paste" "B.Mask") (roundrect_rratio 0.25)
      (net 58 "HPD") (pintype "passive"))
    (pad "2" smd roundrect (at 0.48 0 180) (size 0.59 0.64) (layers "B.Cu" "B.Paste" "B.Mask") (roundrect_rratio 0.25)
      (net 153 "Net-(U3-GPIO4(HPD_TXRX))") (pintype "passive"))
  )
	(footprint "antmicro-footprints:C_0402_1005Metric" (layer "B.Cu")
    (at 136.75 77.9)
    (descr "Capacitor SMD 0402")
    (tags "capacitor SMD 0402")
    (property "Author" "Antmicro")
    (property "Dielectric" "")
    (property "License" "Apache-2.0")
    (property "MPN" "C1005X6S1A105K050BC")
    (property "Manufacturer" "TDK")
    (property "Sheetfile" "tb-power.kicad_sch")
    (property "Sheetname" "Thunderbolt Controller - Power")
    (property "Val" "1u")
    (property "Voltage" "")
    (property "ki_description" "SMD Multilayer Ceramic Capacitor, 1 µF, 10 V, 0402 [1005 Metric], ± 10%, X6S, C")
    (property "ki_keywords" "0402, SMT, CAPACITOR, PASSIVE, CERAMIC, MLCC")
    (attr smd)
    (fp_text reference "C72" (at 17.682 7.825 180) (layer "B.SilkS")
        (effects (font (size 0.7 0.7) (thickness 0.15)) (justify left bottom mirror))
    )
    (fp_text value "C_1u_0402" (at -1.022927 -2.155213 180) (layer "B.Fab")
        (effects (font (size 0.7 0.7) (thickness 0.15)) (justify left bottom mirror))
    )
    (fp_text user "Author: Antmicro" (at -0.939 -3.399 180) (layer "B.Fab") hide
        (effects (font (size 0.7 0.7) (thickness 0.15)) (justify left bottom mirror))
    )
    (fp_text user "${REFERENCE}" (at -0.939 -4.599 180) (layer "B.Fab") hide
        (effects (font (size 0.7 0.7) (thickness 0.15)) (justify left bottom mirror))
    )
    (fp_text user "License: Apache-2.0" (at -0.939 -5.799 180) (layer "B.Fab") hide
        (effects (font (size 0.7 0.7) (thickness 0.15)) (justify left bottom mirror))
    )
    (fp_rect (start -0.925 0.47) (end 0.925 -0.47)
      (stroke (width 0.05) (type default)) (fill none) (layer "B.CrtYd"))
    (fp_line (start -0.494 -0.248) (end -0.494 0.25)
      (stroke (width 0.15) (type solid)) (layer "B.Fab"))
    (fp_line (start -0.494 0.25) (end 0.504 0.25)
      (stroke (width 0.15) (type solid)) (layer "B.Fab"))
    (fp_line (start 0.504 -0.248) (end -0.494 -0.248)
      (stroke (width 0.15) (type solid)) (layer "B.Fab"))
    (fp_line (start 0.504 0.25) (end 0.504 -0.248)
      (stroke (width 0.15) (type solid)) (layer "B.Fab"))
    (pad "1" smd roundrect (at -0.48 0) (size 0.59 0.64) (layers "B.Cu" "B.Paste" "B.Mask") (roundrect_rratio 0.25)
      (net 1 "GND") (pintype "passive"))
    (pad "2" smd roundrect (at 0.48 0) (size 0.59 0.64) (layers "B.Cu" "B.Paste" "B.Mask") (roundrect_rratio 0.25)
      (net 2 "3V3_SYS") (pintype "passive"))
  )
)
